(kicad_pcb
	(version 20240108)
	(generator "pcbnew")
	(generator_version "8.0")
	(general
		(thickness 1.586)
		(legacy_teardrops no)
	)
	(paper "A4")
	(title_block
		(title "GMSL Serializer")
		(date "2024-11-27")
		(rev "1.1.1")
		(company "Antmicro Ltd")
		(comment 1 "www.antmicro.com")
		(comment 9 "footprints 78-82 of 117")
	)
	(layers
		(0 "F.Cu" signal)
		(1 "In1.Cu" power)
		(2 "In2.Cu" power)
		(31 "B.Cu" signal)
		(32 "B.Adhes" user "B.Adhesive")
		(33 "F.Adhes" user "F.Adhesive")
		(34 "B.Paste" user)
		(35 "F.Paste" user)
		(36 "B.SilkS" user "B.Silkscreen")
		(37 "F.SilkS" user "F.Silkscreen")
		(38 "B.Mask" user)
		(39 "F.Mask" user)
		(40 "Dwgs.User" user "User.Drawings")
		(41 "Cmts.User" user "User.Comments")
		(42 "Eco1.User" user "User.Eco1")
		(43 "Eco2.User" user "User.Eco2")
		(44 "Edge.Cuts" user)
		(45 "Margin" user)
		(46 "B.CrtYd" user "B.Courtyard")
		(47 "F.CrtYd" user "F.Courtyard")
		(48 "B.Fab" user)
		(49 "F.Fab" user)
	)
	(footprint "antmicro-footprints:R_0402_1005Metric"
		(layer "F.Cu")
		(at 160.986 98.8)
		(descr "Resistor SMD 0402")
		(tags "resistor SMD 0402")
		(property "Reference" "R11"
			(at -3.069333 -0.6 0)
			(layer "F.SilkS")
			(effects
				(font
					(size 0.7 0.7)
					(thickness 0.15)
				)
				(justify left bottom)
			)
		)
		(property "Value" "R_12k4_0402"
			(at -1.011843 1.772047 0)
			(layer "F.Fab")
			(effects
				(font
					(size 0.7 0.7)
					(thickness 0.15)
				)
				(justify left bottom)
			)
		)
		(property "Footprint" "antmicro-footprints:R_0402_1005Metric"
			(at 0 0 0)
			(layer "F.Fab")
			(hide yes)
			(effects
				(font
					(size 1.27 1.27)
					(thickness 0.15)
				)
			)
		)
		(property "Datasheet" "https://www.bourns.com/docs/product-datasheets/cr.pdf"
			(at 0 0 0)
			(layer "F.Fab")
			(hide yes)
			(effects
				(font
					(size 1.27 1.27)
					(thickness 0.15)
				)
			)
		)
		(property "Author" "Antmicro"
			(at 0 0 0)
			(layer "F.Fab")
			(hide yes)
			(effects
				(font
					(size 1 1)
					(thickness 0.15)
				)
			)
		)
		(property "License" "Apache-2.0"
			(at 0 0 0)
			(layer "F.Fab")
			(hide yes)
			(effects
				(font
					(size 1 1)
					(thickness 0.15)
				)
			)
		)
		(property "MPN" "CR0402-FX-1242GLF"
			(at 0 0 0)
			(layer "F.Fab")
			(hide yes)
			(effects
				(font
					(size 1 1)
					(thickness 0.15)
				)
			)
		)
		(property "Manufacturer" "Bourns"
			(at 0 0 0)
			(layer "F.Fab")
			(hide yes)
			(effects
				(font
					(size 1 1)
					(thickness 0.15)
				)
			)
		)
		(property "Tolerance" "1%"
			(at 0 0 0)
			(layer "F.Fab")
			(hide yes)
			(effects
				(font
					(size 1 1)
					(thickness 0.15)
				)
			)
		)
		(property "Val" "12k4"
			(at 0 0 0)
			(layer "F.Fab")
			(hide yes)
			(effects
				(font
					(size 1 1)
					(thickness 0.15)
				)
			)
		)
		(sheetname "Supply")
		(sheetfile "supply.kicad_sch")
		(attr smd)
		(fp_rect
			(start -0.925 -0.47)
			(end 0.925 0.47)
			(stroke
				(width 0.05)
				(type default)
			)
			(fill none)
			(layer "F.CrtYd")
		)
		(fp_rect
			(start -0.5 -0.25)
			(end 0.5 0.25)
			(stroke
				(width 0.15)
				(type solid)
			)
			(fill none)
			(layer "F.Fab")
		)
		(fp_text user "License: Apache-2.0"
			(at -0.95 5.169 0)
			(layer "F.Fab")
			(hide yes)
			(effects
				(font
					(size 0.7 0.7)
					(thickness 0.15)
				)
				(justify left bottom)
			)
		)
		(fp_text user "Author: Antmicro"
			(at -0.95 4.169 0)
			(layer "F.Fab")
			(hide yes)
			(effects
				(font
					(size 0.7 0.7)
					(thickness 0.15)
				)
				(justify left bottom)
			)
		)
		(fp_text user "${REFERENCE}"
			(at -0.95 3.168 0)
			(layer "F.Fab")
			(hide yes)
			(effects
				(font
					(size 0.7 0.7)
					(thickness 0.15)
				)
				(justify left bottom)
			)
		)
		(pad "1" smd roundrect
			(at -0.48 0)
			(size 0.59 0.64)
			(layers "F.Cu" "F.Paste" "F.Mask")
			(roundrect_rratio 0.25)
			(net 65 "/Supply/FB_1V8")
			(pintype "passive")
		)
		(pad "2" smd roundrect
			(at 0.48 0)
			(size 0.59 0.64)
			(layers "F.Cu" "F.Paste" "F.Mask")
			(roundrect_rratio 0.25)
			(net 8 "/Supply/OUT_1V8")
			(pintype "passive")
		)
	)
	(footprint "antmicro-footprints:TSOT23-6"
		(layer "F.Cu")
		(at 142.195 83.350142 180)
		(property "Reference" "U3"
			(at -0.905 2.500142 0)
			(layer "F.SilkS")
			(effects
				(font
					(size 0.7 0.7)
					(thickness 0.15)
				)
				(justify right top)
			)
		)
		(property "Value" "AP62301_TSOT"
			(at 0.13 1.85 0)
			(layer "F.Fab")
			(effects
				(font
					(size 0.7 0.7)
					(thickness 0.15)
				)
				(justify right top)
			)
		)
		(property "Footprint" "antmicro-footprints:TSOT23-6"
			(at 0 0 0)
			(layer "F.Fab")
			(hide yes)
			(effects
				(font
					(size 1.27 1.27)
					(thickness 0.15)
				)
			)
		)
		(property "Datasheet" "https://www.diodes.com/assets/Datasheets/AP62300_AP62301_AP62300T.pdf"
			(at 0 0 0)
			(layer "F.Fab")
			(hide yes)
			(effects
				(font
					(size 1.27 1.27)
					(thickness 0.15)
				)
			)
		)
		(property "MPN" "AP62301WU-7"
			(at 0 0 180)
			(unlocked yes)
			(layer "F.Fab")
			(hide yes)
			(effects
				(font
					(size 1 1)
					(thickness 0.15)
				)
			)
		)
		(property "Manufacturer" "Diodes Incorporated"
			(at 0 0 180)
			(unlocked yes)
			(layer "F.Fab")
			(hide yes)
			(effects
				(font
					(size 1 1)
					(thickness 0.15)
				)
			)
		)
		(property "Author" "Antmicro"
			(at 0 0 180)
			(unlocked yes)
			(layer "F.Fab")
			(hide yes)
			(effects
				(font
					(size 1 1)
					(thickness 0.15)
				)
			)
		)
		(property "License" "Apache-2.0"
			(at 0 0 180)
			(unlocked yes)
			(layer "F.Fab")
			(hide yes)
			(effects
				(font
					(size 1 1)
					(thickness 0.15)
				)
			)
		)
		(sheetname "Supply")
		(sheetfile "supply.kicad_sch")
		(attr smd)
		(fp_line
			(start 1 1.55)
			(end 1 1.4)
			(stroke
				(width 0.15)
				(type solid)
			)
			(layer "F.SilkS")
		)
		(fp_line
			(start 1 1.55)
			(end -1 1.55)
			(stroke
				(width 0.15)
				(type solid)
			)
			(layer "F.SilkS")
		)
		(fp_line
			(start 1 -1.497)
			(end 1 -1.375)
			(stroke
				(width 0.15)
				(type solid)
			)
			(layer "F.SilkS")
		)
		(fp_line
			(start 1 -1.497)
			(end -1 -1.5)
			(stroke
				(width 0.15)
				(type solid)
			)
			(layer "F.SilkS")
		)
		(fp_line
			(start -1 1.55)
			(end -1 1.4)
			(stroke
				(width 0.15)
				(type solid)
			)
			(layer "F.SilkS")
		)
		(fp_line
			(start -1 -1.5)
			(end -1 -1.375)
			(stroke
				(width 0.15)
				(type solid)
			)
			(layer "F.SilkS")
		)
		(fp_circle
			(center -1.44 -1.5)
			(end -1.39 -1.5)
			(stroke
				(width 0.15)
				(type solid)
			)
			(fill solid)
			(layer "F.SilkS")
		)
		(fp_rect
			(start 1.93 -1.7)
			(end -1.93 1.7)
			(stroke
				(width 0.05)
				(type solid)
			)
			(fill none)
			(layer "F.CrtYd")
		)
		(fp_line
			(start -0.45 -1.521)
			(end -0.876 -1.096)
			(stroke
				(width 0.15)
				(type solid)
			)
			(layer "F.Fab")
		)
		(fp_rect
			(start 0.875 1.528)
			(end -0.875 -1.525)
			(stroke
				(width 0.15)
				(type solid)
			)
			(fill none)
			(layer "F.Fab")
		)
		(fp_text user "License: Apache-2.0"
			(at -1.93 6.199 0)
			(layer "F.Fab")
			(hide yes)
			(effects
				(font
					(size 0.7 0.7)
					(thickness 0.15)
				)
				(justify right top)
			)
		)
		(fp_text user "${REFERENCE}"
			(at -1.93 3.8 0)
			(layer "F.Fab")
			(hide yes)
			(effects
				(font
					(size 0.7 0.7)
					(thickness 0.15)
				)
				(justify right top)
			)
		)
		(fp_text user "Author: Antmicro"
			(at -1.93 5 0)
			(layer "F.Fab")
			(hide yes)
			(effects
				(font
					(size 0.7 0.7)
					(thickness 0.15)
				)
				(justify right top)
			)
		)
		(pad "1" smd rect
			(at -1.301 -0.947 90)
			(size 0.7 1.2)
			(layers "F.Cu" "F.Paste" "F.Mask")
			(net 1 "GND")
			(pinfunction "GND")
			(pintype "power_in")
		)
		(pad "2" smd rect
			(at -1.301 0.004 90)
			(size 0.7 1.2)
			(layers "F.Cu" "F.Paste" "F.Mask")
			(net 72 "/Supply/SW_3V3")
			(pinfunction "SW")
			(pintype "power_out")
		)
		(pad "3" smd rect
			(at -1.301 0.954 90)
			(size 0.7 1.2)
			(layers "F.Cu" "F.Paste" "F.Mask")
			(net 2 "+12V")
			(pinfunction "VIN")
			(pintype "power_in")
		)
		(pad "4" smd rect
			(at 1.299 0.954 90)
			(size 0.7 1.2)
			(layers "F.Cu" "F.Paste" "F.Mask")
			(net 96 "/Supply/FB_3V3")
			(pinfunction "FB")
			(pintype "input")
		)
		(pad "5" smd rect
			(at 1.299 0.004 90)
			(size 0.7 1.2)
			(layers "F.Cu" "F.Paste" "F.Mask")
			(net 97 "/Supply/EN_3V3")
			(pinfunction "EN")
			(pintype "input")
		)
		(pad "6" smd rect
			(at 1.299 -0.947 90)
			(size 0.7 1.2)
			(layers "F.Cu" "F.Paste" "F.Mask")
			(net 93 "Net-(U3-BST)")
			(pinfunction "BST")
			(pintype "output")
		)
	)
	(footprint "antmicro-footprints:L_Coilcraft-PFL1609"
		(layer "F.Cu")
		(at 156.337 92.2 180)
		(property "Reference" "L5"
			(at -2.273 -0.41 180)
			(layer "F.SilkS")
			(effects
				(font
					(size 0.7 0.7)
					(thickness 0.15)
				)
				(justify right bottom)
			)
		)
		(property "Value" "L_470n_1A_Coilcraft-PFL1609"
			(at 0 2 0)
			(layer "F.Fab")
			(effects
				(font
					(size 0.7 0.7)
					(thickness 0.15)
				)
				(justify right bottom)
			)
		)
		(property "Footprint" "antmicro-footprints:L_Coilcraft-PFL1609"
			(at 0 0 180)
			(layer "F.Fab")
			(hide yes)
			(effects
				(font
					(size 1.27 1.27)
					(thickness 0.15)
				)
			)
		)
		(property "Datasheet" "https://www.coilcraft.com/getmedia/2f4cd442-d64d-4413-a518-12fcfd03318d/pfl1609.pdf"
			(at 0 0 180)
			(layer "F.Fab")
			(hide yes)
			(effects
				(font
					(size 1.27 1.27)
					(thickness 0.15)
				)
			)
		)
		(property "Author" "Antmicro"
			(at 312.674 184.4 0)
			(layer "F.Fab")
			(hide yes)
			(effects
				(font
					(size 1 1)
					(thickness 0.15)
				)
			)
		)
		(property "IMax" "1 A"
			(at 312.674 184.4 0)
			(layer "F.Fab")
			(hide yes)
			(effects
				(font
					(size 1 1)
					(thickness 0.15)
				)
			)
		)
		(property "ISat" "0.99 A"
			(at 312.674 184.4 0)
			(layer "F.Fab")
			(hide yes)
			(effects
				(font
					(size 1 1)
					(thickness 0.15)
				)
			)
		)
		(property "License" "Apache-2.0"
			(at 312.674 184.4 0)
			(layer "F.Fab")
			(hide yes)
			(effects
				(font
					(size 1 1)
					(thickness 0.15)
				)
			)
		)
		(property "MPN" "PFL1609-471"
			(at 312.674 184.4 0)
			(layer "F.Fab")
			(hide yes)
			(effects
				(font
					(size 1 1)
					(thickness 0.15)
				)
			)
		)
		(property "Manufacturer" "Coilcraft"
			(at 312.674 184.4 0)
			(layer "F.Fab")
			(hide yes)
			(effects
				(font
					(size 1 1)
					(thickness 0.15)
				)
			)
		)
		(property "Size" "1.07x1.8"
			(at 312.674 184.4 0)
			(layer "F.Fab")
			(hide yes)
			(effects
				(font
					(size 1 1)
					(thickness 0.15)
				)
			)
		)
		(property "Val" "470n/0.99A"
			(at 312.674 184.4 0)
			(layer "F.Fab")
			(hide yes)
			(effects
				(font
					(size 1 1)
					(thickness 0.15)
				)
			)
		)
		(sheetname "GMSL Connector")
		(sheetfile "GMSL.kicad_sch")
		(attr smd)
		(fp_line
			(start -0.23 0.45)
			(end 0.23 0.45)
			(stroke
				(width 0.15)
				(type solid)
			)
			(layer "F.SilkS")
		)
		(fp_line
			(start -0.23 -0.45)
			(end 0.23 -0.45)
			(stroke
				(width 0.15)
				(type solid)
			)
			(layer "F.SilkS")
		)
		(fp_rect
			(start -1.2 -0.84)
			(end 1.2 0.84)
			(stroke
				(width 0.05)
				(type solid)
			)
			(fill none)
			(layer "F.CrtYd")
		)
		(fp_rect
			(start -0.9 -0.535)
			(end 0.9 0.535)
			(stroke
				(width 0.15)
				(type solid)
			)
			(fill none)
			(layer "F.Fab")
		)
		(fp_text user "License: Apache-2.0"
			(at -1.35 6.4 0)
			(layer "F.Fab")
			(hide yes)
			(effects
				(font
					(size 0.7 0.7)
					(thickness 0.15)
				)
				(justify right bottom)
			)
		)
		(fp_text user "${REFERENCE}"
			(at -1.35 4 0)
			(layer "F.Fab")
			(hide yes)
			(effects
				(font
					(size 0.7 0.7)
					(thickness 0.15)
				)
				(justify right bottom)
			)
		)
		(fp_text user "Author: Antmicro"
			(at -1.35 5.2 0)
			(layer "F.Fab")
			(hide yes)
			(effects
				(font
					(size 0.7 0.7)
					(thickness 0.15)
				)
				(justify right bottom)
			)
		)
		(pad "1" smd roundrect
			(at -0.635 0 180)
			(size 0.64 1.02)
			(layers "F.Cu" "F.Paste" "F.Mask")
			(roundrect_rratio 0.15)
			(net 59 "Net-(L4-Pad2)")
			(pintype "passive")
		)
		(pad "2" smd roundrect
			(at 0.635 0 180)
			(size 0.64 1.02)
			(layers "F.Cu" "F.Paste" "F.Mask")
			(roundrect_rratio 0.15)
			(net 60 "Net-(L5-Pad2)")
			(pintype "passive")
		)
	)
	(footprint "antmicro-footprints:R_0402_1005Metric"
		(layer "F.Cu")
		(at 141.1 115.55 90)
		(descr "Resistor SMD 0402")
		(tags "resistor SMD 0402")
		(property "Reference" "R15"
			(at 0.75 0.5 90)
			(layer "F.SilkS")
			(effects
				(font
					(size 0.7 0.7)
					(thickness 0.15)
				)
				(justify left bottom)
			)
		)
		(property "Value" "R_470R_0402"
			(at -1.011843 1.772047 90)
			(layer "F.Fab")
			(effects
				(font
					(size 0.7 0.7)
					(thickness 0.15)
				)
				(justify left bottom)
			)
		)
		(property "Footprint" "antmicro-footprints:R_0402_1005Metric"
			(at 0 0 90)
			(layer "F.Fab")
			(hide yes)
			(effects
				(font
					(size 1.27 1.27)
					(thickness 0.15)
				)
			)
		)
		(property "Datasheet" "https://www.bourns.com/docs/product-datasheets/cr.pdf"
			(at 0 0 90)
			(layer "F.Fab")
			(hide yes)
			(effects
				(font
					(size 1.27 1.27)
					(thickness 0.15)
				)
			)
		)
		(property "Author" "Antmicro"
			(at 256.65 -25.55 0)
			(layer "F.Fab")
			(hide yes)
			(effects
				(font
					(size 1 1)
					(thickness 0.15)
				)
			)
		)
		(property "License" "Apache-2.0"
			(at 256.65 -25.55 0)
			(layer "F.Fab")
			(hide yes)
			(effects
				(font
					(size 1 1)
					(thickness 0.15)
				)
			)
		)
		(property "MPN" "CR0402-FX-4700GLF"
			(at 256.65 -25.55 0)
			(layer "F.Fab")
			(hide yes)
			(effects
				(font
					(size 1 1)
					(thickness 0.15)
				)
			)
		)
		(property "Manufacturer" "Bourns"
			(at 256.65 -25.55 0)
			(layer "F.Fab")
			(hide yes)
			(effects
				(font
					(size 1 1)
					(thickness 0.15)
				)
			)
		)
		(property "Tolerance" "1%"
			(at 256.65 -25.55 0)
			(layer "F.Fab")
			(hide yes)
			(effects
				(font
					(size 1 1)
					(thickness 0.15)
				)
			)
		)
		(property "Val" "470R"
			(at 256.65 -25.55 0)
			(layer "F.Fab")
			(hide yes)
			(effects
				(font
					(size 1 1)
					(thickness 0.15)
				)
			)
		)
		(sheetname "Supply")
		(sheetfile "supply.kicad_sch")
		(attr smd)
		(fp_rect
			(start -0.925 -0.47)
			(end 0.925 0.47)
			(stroke
				(width 0.05)
				(type default)
			)
			(fill none)
			(layer "F.CrtYd")
		)
		(fp_rect
			(start -0.5 -0.25)
			(end 0.5 0.25)
			(stroke
				(width 0.15)
				(type solid)
			)
			(fill none)
			(layer "F.Fab")
		)
		(fp_text user "License: Apache-2.0"
			(at -0.95 5.169 90)
			(layer "F.Fab")
			(hide yes)
			(effects
				(font
					(size 0.7 0.7)
					(thickness 0.15)
				)
				(justify left bottom)
			)
		)
		(fp_text user "Author: Antmicro"
			(at -0.95 4.169 90)
			(layer "F.Fab")
			(hide yes)
			(effects
				(font
					(size 0.7 0.7)
					(thickness 0.15)
				)
				(justify left bottom)
			)
		)
		(fp_text user "${REFERENCE}"
			(at -0.95 3.168 90)
			(layer "F.Fab")
			(hide yes)
			(effects
				(font
					(size 0.7 0.7)
					(thickness 0.15)
				)
				(justify left bottom)
			)
		)
		(pad "1" smd roundrect
			(at -0.48 0 90)
			(size 0.59 0.64)
			(layers "F.Cu" "F.Paste" "F.Mask")
			(roundrect_rratio 0.25)
			(net 1 "GND")
			(pintype "passive")
		)
		(pad "2" smd roundrect
			(at 0.48 0 90)
			(size 0.59 0.64)
			(layers "F.Cu" "F.Paste" "F.Mask")
			(roundrect_rratio 0.25)
			(net 69 "Net-(D5-C)")
			(pintype "passive")
		)
	)
	(footprint "antmicro-footprints:MP_Pad6mm_Drill3mm"
		(layer "F.Cu")
		(at 134.15 117.35)
		(property "Reference" "MP3"
			(at 0 -3.2 0)
			(layer "F.SilkS")
			(hide yes)
			(effects
				(font
					(size 0.7 0.7)
					(thickness 0.15)
				)
				(justify left bottom)
			)
		)
		(property "Value" "MP_Pad6mm_Drill3mm"
			(at 0 3.9 0)
			(layer "F.Fab")
			(effects
				(font
					(size 0.7 0.7)
					(thickness 0.15)
				)
				(justify left bottom)
			)
		)
		(property "Footprint" "antmicro-footprints:MP_Pad6mm_Drill3mm"
			(at 0 0 0)
			(layer "F.Fab")
			(hide yes)
			(effects
				(font
					(size 1.27 1.27)
					(thickness 0.15)
				)
			)
		)
		(property "Author" "Antmicro"
			(at 0 0 0)
			(layer "F.Fab")
			(hide yes)
			(effects
				(font
					(size 1 1)
					(thickness 0.15)
				)
			)
		)
		(property "License" "Apache-2.0"
			(at 0 0 0)
			(layer "F.Fab")
			(hide yes)
			(effects
				(font
					(size 1 1)
					(thickness 0.15)
				)
			)
		)
		(sheetname "Root")
		(sheetfile "gmsl-serializer.kicad_sch")
		(attr exclude_from_pos_files exclude_from_bom)
		(fp_circle
			(center 0 0)
			(end 3.25 0)
			(stroke
				(width 0.05)
				(type default)
			)
			(fill none)
			(layer "F.CrtYd")
		)
		(fp_text user "License: Apache-2.0"
			(at -0.178 8.425 0)
			(layer "F.Fab")
			(hide yes)
			(effects
				(font
					(size 0.7 0.7)
					(thickness 0.15)
				)
				(justify left bottom)
			)
		)
		(fp_text user "Author: Antmicro"
			(at -0.178 7.225 0)
			(layer "F.Fab")
			(hide yes)
			(effects
				(font
					(size 0.7 0.7)
					(thickness 0.15)
				)
				(justify left bottom)
			)
		)
		(fp_text user "${REFERENCE}"
			(at -0.178 6.025 0)
			(layer "F.Fab")
			(hide yes)
			(effects
				(font
					(size 0.7 0.7)
					(thickness 0.15)
				)
				(justify left bottom)
			)
		)
		(pad "1" thru_hole circle
			(at 0 0)
			(size 6 6)
			(drill 3)
			(layers "*.Cu" "*.Mask")
			(remove_unused_layers no)
			(net 1 "GND")
			(pintype "passive")
			(solder_paste_margin_ratio -1)
		)
	)
)
